# S9S_MB_2U (Grand Teton) — schematic netlist excerpt (pin names and nets, part order shuffled) for the footprints in the layout excerpt that follows; sources: Cadence DE-HDL packaged netlist, KiCad conversion of 03242023_DA0F0TMBIJ0_F0T_Motherboard_J_brd_V01_OCP.brd

C510  Q_CAP  47UF 4V 20% X6S  pkg C0805  page 76 : A = PVCCFA_EHV_FIVRA_CPU0 ; B = GND
R16  Q_RES  0 5% CHIP  pkg 0402LF  page 14 : A = SVID_CLK1_CPU0 ; B = SVID_CLK1_CPU0_R
C1297  Q_CAP  1000PF 50V 5% X7R  pkg 0402  page 300 : A = PWRGD_PVNN_MAIN_CPU1 ; B = GND

(kicad_pcb
	(version 20260206)
	(generator "pcbnew")
	(generator_version "10.0")
	(general
		(thickness 1.6)
		(legacy_teardrops no)
	)
	(paper "A4")
	(title_block
		(title "03242023_DA0F0TMBIJ0_F0T_Motherboard_J_brd_V01_OCP.brd")
		(comment 1 "Grand Teton / footprints 5157-5159 of 6105")
	)
	(layers
		(0 "F.Cu" signal "TOP")
		(4 "In1.Cu" signal "GND")
		(6 "In2.Cu" signal "IN1")
		(8 "In3.Cu" signal "GND1")
		(10 "In4.Cu" signal "IN2")
		(12 "In5.Cu" signal "GND2")
		(14 "In6.Cu" signal "IN3")
		(16 "In7.Cu" signal "GND3")
		(18 "In8.Cu" signal "VCC")
		(20 "In9.Cu" signal "VCC1")
		(22 "In10.Cu" signal "GND4")
		(24 "In11.Cu" signal "IN4")
		(26 "In12.Cu" signal "GND5")
		(28 "In13.Cu" signal "IN5")
		(30 "In14.Cu" signal "GND6")
		(32 "In15.Cu" signal "IN6")
		(34 "In16.Cu" signal "GND7")
		(2 "B.Cu" signal "BOTTOM")
		(9 "F.Adhes" user "F.Adhesive")
		(11 "B.Adhes" user "B.Adhesive")
		(13 "F.Paste" user "Package Geometry/Pastemask Top")
		(15 "B.Paste" user "Package Geometry/Pastemask Bottom")
		(5 "F.SilkS" user "Ref Des/Silkscreen Top")
		(7 "B.SilkS" user "Ref Des/Silkscreen Bottom")
		(1 "F.Mask" user "Board Geometry/Soldermask Top")
		(3 "B.Mask" user "Board Geometry/Soldermask Bottom")
		(17 "Dwgs.User" user "User.Drawings")
		(19 "Cmts.User" user "User.Comments")
		(21 "Eco1.User" user "User.Eco1")
		(23 "Eco2.User" user "User.Eco2")
		(25 "Edge.Cuts" user "Board Geometry/Outline")
		(27 "Margin" user)
		(31 "F.CrtYd" user "Package Geometry/Place Bound Top")
		(29 "B.CrtYd" user "Package Geometry/Place Bound Bottom")
		(35 "F.Fab" user "Ref Des/Assembly Top")
		(33 "B.Fab" user "Ref Des/Assembly Bottom")
	)
	(footprint ""
		(layer "B.Cu")
		(at 22.960584 -176.253902 -90)
		(property "Reference" "C1297"
			(at 0 0 90)
			(layer "B.SilkS")
			(hide yes)
			(effects
				(font
					(size 1.27 1.27)
				)
				(justify mirror)
			)
		)
		(property "Value" ""
			(at 0 0 90)
			(layer "B.Fab")
			(effects
				(font
					(size 1.27 1.27)
				)
				(justify mirror)
			)
		)
		(duplicate_pad_numbers_are_jumpers no)
		(fp_line
			(start -0.7874 0.4064)
			(end 0.7874 0.4064)
			(stroke
				(width 0.1524)
				(type default)
			)
			(layer "B.SilkS")
		)
		(fp_line
			(start 0.7874 0.4064)
			(end 0.7874 -0.4064)
			(stroke
				(width 0.1524)
				(type default)
			)
			(layer "B.SilkS")
		)
		(fp_line
			(start -0.7874 -0.4064)
			(end -0.7874 0.4064)
			(stroke
				(width 0.1524)
				(type default)
			)
			(layer "B.SilkS")
		)
		(fp_line
			(start 0.7874 -0.4064)
			(end -0.7874 -0.4064)
			(stroke
				(width 0.1524)
				(type default)
			)
			(layer "B.SilkS")
		)
		(fp_line
			(start -0.67945 0.3048)
			(end -0.120396 0.3048)
			(stroke
				(width 0.1)
				(type default)
			)
			(layer "B.Fab")
		)
		(fp_line
			(start -0.120396 0.3048)
			(end -0.120396 0.2794)
			(stroke
				(width 0.1)
				(type default)
			)
			(layer "B.Fab")
		)
		(fp_line
			(start 0.12065 0.3048)
			(end 0.67945 0.3048)
			(stroke
				(width 0.1)
				(type default)
			)
			(layer "B.Fab")
		)
		(fp_line
			(start 0.67945 0.3048)
			(end 0.67945 -0.305054)
			(stroke
				(width 0.1)
				(type default)
			)
			(layer "B.Fab")
		)
		(fp_line
			(start -0.120396 0.2794)
			(end 0.12065 0.2794)
			(stroke
				(width 0.1)
				(type default)
			)
			(layer "B.Fab")
		)
		(fp_line
			(start 0.12065 0.2794)
			(end 0.12065 0.3048)
			(stroke
				(width 0.1)
				(type default)
			)
			(layer "B.Fab")
		)
		(fp_line
			(start -0.12065 -0.2794)
			(end -0.12065 -0.3048)
			(stroke
				(width 0.1)
				(type default)
			)
			(layer "B.Fab")
		)
		(fp_line
			(start 0.12065 -0.2794)
			(end -0.12065 -0.2794)
			(stroke
				(width 0.1)
				(type default)
			)
			(layer "B.Fab")
		)
		(fp_line
			(start -0.67945 -0.3048)
			(end -0.67945 0.3048)
			(stroke
				(width 0.1)
				(type default)
			)
			(layer "B.Fab")
		)
		(fp_line
			(start -0.12065 -0.3048)
			(end -0.67945 -0.3048)
			(stroke
				(width 0.1)
				(type default)
			)
			(layer "B.Fab")
		)
		(fp_line
			(start 0.12065 -0.305054)
			(end 0.12065 -0.2794)
			(stroke
				(width 0.1)
				(type default)
			)
			(layer "B.Fab")
		)
		(fp_line
			(start 0.67945 -0.305054)
			(end 0.12065 -0.305054)
			(stroke
				(width 0.1)
				(type default)
			)
			(layer "B.Fab")
		)
		(pad "1" smd circle
			(at 0.40005 0 90)
			(size 0 0)
			(layers "B.Cu" "B.Mask" "B.Paste")
			(net "PWRGD_PVNN_MAIN_CPU1")
		)
		(pad "2" smd circle
			(at -0.40005 0 90)
			(size 0 0)
			(layers "B.Cu" "B.Mask" "B.Paste")
			(net "GND")
		)
	)
	(footprint ""
		(layer "B.Cu")
		(at 307.148738 -194.71767 90)
		(property "Reference" "R16"
			(at 0 0 90)
			(layer "B.SilkS")
			(hide yes)
			(effects
				(font
					(size 1.27 1.27)
				)
				(justify mirror)
			)
		)
		(property "Value" ""
			(at 0 0 90)
			(layer "B.Fab")
			(effects
				(font
					(size 1.27 1.27)
				)
				(justify mirror)
			)
		)
		(duplicate_pad_numbers_are_jumpers no)
		(fp_line
			(start 0.7874 -0.4064)
			(end -0.7874 -0.4064)
			(stroke
				(width 0.1524)
				(type default)
			)
			(layer "B.SilkS")
		)
		(fp_line
			(start -0.7874 -0.4064)
			(end -0.7874 0.4064)
			(stroke
				(width 0.1524)
				(type default)
			)
			(layer "B.SilkS")
		)
		(fp_line
			(start 0.7874 0.4064)
			(end 0.7874 -0.4064)
			(stroke
				(width 0.1524)
				(type default)
			)
			(layer "B.SilkS")
		)
		(fp_line
			(start -0.7874 0.4064)
			(end 0.7874 0.4064)
			(stroke
				(width 0.1524)
				(type default)
			)
			(layer "B.SilkS")
		)
		(fp_line
			(start 0.67945 -0.305054)
			(end 0.12065 -0.305054)
			(stroke
				(width 0.1)
				(type default)
			)
			(layer "B.Fab")
		)
		(fp_line
			(start 0.12065 -0.305054)
			(end 0.12065 -0.2794)
			(stroke
				(width 0.1)
				(type default)
			)
			(layer "B.Fab")
		)
		(fp_line
			(start -0.12065 -0.3048)
			(end -0.67945 -0.3048)
			(stroke
				(width 0.1)
				(type default)
			)
			(layer "B.Fab")
		)
		(fp_line
			(start -0.67945 -0.3048)
			(end -0.67945 0.3048)
			(stroke
				(width 0.1)
				(type default)
			)
			(layer "B.Fab")
		)
		(fp_line
			(start 0.12065 -0.2794)
			(end -0.12065 -0.2794)
			(stroke
				(width 0.1)
				(type default)
			)
			(layer "B.Fab")
		)
		(fp_line
			(start -0.12065 -0.2794)
			(end -0.12065 -0.3048)
			(stroke
				(width 0.1)
				(type default)
			)
			(layer "B.Fab")
		)
		(fp_line
			(start 0.12065 0.2794)
			(end 0.12065 0.3048)
			(stroke
				(width 0.1)
				(type default)
			)
			(layer "B.Fab")
		)
		(fp_line
			(start -0.120396 0.2794)
			(end 0.12065 0.2794)
			(stroke
				(width 0.1)
				(type default)
			)
			(layer "B.Fab")
		)
		(fp_line
			(start 0.67945 0.3048)
			(end 0.67945 -0.305054)
			(stroke
				(width 0.1)
				(type default)
			)
			(layer "B.Fab")
		)
		(fp_line
			(start 0.12065 0.3048)
			(end 0.67945 0.3048)
			(stroke
				(width 0.1)
				(type default)
			)
			(layer "B.Fab")
		)
		(fp_line
			(start -0.120396 0.3048)
			(end -0.120396 0.2794)
			(stroke
				(width 0.1)
				(type default)
			)
			(layer "B.Fab")
		)
		(fp_line
			(start -0.67945 0.3048)
			(end -0.120396 0.3048)
			(stroke
				(width 0.1)
				(type default)
			)
			(layer "B.Fab")
		)
		(pad "1" smd circle
			(at 0.40005 0 270)
			(size 0 0)
			(layers "B.Cu" "B.Mask" "B.Paste")
			(net "SVID_CLK1_CPU0")
		)
		(pad "2" smd circle
			(at -0.40005 0 270)
			(size 0 0)
			(layers "B.Cu" "B.Mask" "B.Paste")
			(net "SVID_CLK1_CPU0_R")
		)
	)
	(footprint ""
		(layer "B.Cu")
		(at 412.548324 -256.636266 -90)
		(property "Reference" "C510"
			(at 0 0 90)
			(layer "B.SilkS")
			(hide yes)
			(effects
				(font
					(size 1.27 1.27)
				)
				(justify mirror)
			)
		)
		(property "Value" ""
			(at 0 0 90)
			(layer "B.Fab")
			(effects
				(font
					(size 1.27 1.27)
				)
				(justify mirror)
			)
		)
		(duplicate_pad_numbers_are_jumpers no)
		(fp_line
			(start -1.524 0.762)
			(end 1.524 0.762)
			(stroke
				(width 0.1524)
				(type default)
			)
			(layer "B.SilkS")
		)
		(fp_line
			(start 1.524 0.762)
			(end 1.524 -0.762)
			(stroke
				(width 0.1524)
				(type default)
			)
			(layer "B.SilkS")
		)
		(fp_line
			(start -1.524 -0.762)
			(end -1.524 0.762)
			(stroke
				(width 0.1524)
				(type default)
			)
			(layer "B.SilkS")
		)
		(fp_line
			(start 1.524 -0.762)
			(end -1.524 -0.762)
			(stroke
				(width 0.1524)
				(type default)
			)
			(layer "B.SilkS")
		)
		(fp_line
			(start -1.1049 0.724916)
			(end -1.1049 -0.724916)
			(stroke
				(width 0.1)
				(type default)
			)
			(layer "B.Fab")
		)
		(fp_line
			(start 1.1049 0.724916)
			(end -1.1049 0.724916)
			(stroke
				(width 0.1)
				(type default)
			)
			(layer "B.Fab")
		)
		(fp_line
			(start -1.1049 -0.724916)
			(end 1.1049 -0.724916)
			(stroke
				(width 0.1)
				(type default)
			)
			(layer "B.Fab")
		)
		(fp_line
			(start 1.1049 -0.724916)
			(end 1.1049 0.724916)
			(stroke
				(width 0.1)
				(type default)
			)
			(layer "B.Fab")
		)
		(pad "1" smd rect
			(at 0.889 0 270)
			(size 1.016 1.27)
			(layers "B.Cu" "B.Mask" "B.Paste")
			(net "PVCCFA_EHV_FIVRA_CPU0")
		)
		(pad "2" smd rect
			(at -0.889 0 270)
			(size 1.016 1.27)
			(layers "B.Cu" "B.Mask" "B.Paste")
			(net "GND")
		)
	)
)
